# S9S_MB_2U (Grand Teton) — schematic netlist excerpt (pin names and nets, part order shuffled) for the footprints in the layout excerpt that follows; sources: Cadence DE-HDL packaged netlist, KiCad conversion of 03242023_DA0F0TMBIJ0_F0T_Motherboard_J_brd_V01_OCP.brd

R1742  Q_RES  10K 1% EMPTY  pkg 0402LF  page 220 : A = FM_RST_PERST_BIT0 ; B = GND
PL120  Q_INDUCTOR  4.7UH IND  pkg SMLF  page 282 : \1\ = SW_PVNN_MAIN_CPU0_SW ; \2\ = PVNN_MAIN_CPU0
PC255_P0_5  Q_CAP  1UF 16V 10% X6S  pkg C0402  page 269 : A = SW_P12V_PVCCIN_CPU0_FLT ; B = GND

(kicad_pcb
	(version 20260206)
	(generator "pcbnew")
	(generator_version "10.0")
	(general
		(thickness 1.6)
		(legacy_teardrops no)
	)
	(paper "A4")
	(title_block
		(title "03242023_DA0F0TMBIJ0_F0T_Motherboard_J_brd_V01_OCP.brd")
		(comment 1 "Grand Teton / footprints 11-13 of 6105")
	)
	(layers
		(0 "F.Cu" signal "TOP")
		(4 "In1.Cu" signal "GND")
		(6 "In2.Cu" signal "IN1")
		(8 "In3.Cu" signal "GND1")
		(10 "In4.Cu" signal "IN2")
		(12 "In5.Cu" signal "GND2")
		(14 "In6.Cu" signal "IN3")
		(16 "In7.Cu" signal "GND3")
		(18 "In8.Cu" signal "VCC")
		(20 "In9.Cu" signal "VCC1")
		(22 "In10.Cu" signal "GND4")
		(24 "In11.Cu" signal "IN4")
		(26 "In12.Cu" signal "GND5")
		(28 "In13.Cu" signal "IN5")
		(30 "In14.Cu" signal "GND6")
		(32 "In15.Cu" signal "IN6")
		(34 "In16.Cu" signal "GND7")
		(2 "B.Cu" signal "BOTTOM")
		(9 "F.Adhes" user "F.Adhesive")
		(11 "B.Adhes" user "B.Adhesive")
		(13 "F.Paste" user "Package Geometry/Pastemask Top")
		(15 "B.Paste" user "Package Geometry/Pastemask Bottom")
		(5 "F.SilkS" user "Ref Des/Silkscreen Top")
		(7 "B.SilkS" user "Ref Des/Silkscreen Bottom")
		(1 "F.Mask" user "Board Geometry/Soldermask Top")
		(3 "B.Mask" user "Board Geometry/Soldermask Bottom")
		(17 "Dwgs.User" user "User.Drawings")
		(19 "Cmts.User" user "User.Comments")
		(21 "Eco1.User" user "User.Eco1")
		(23 "Eco2.User" user "User.Eco2")
		(25 "Edge.Cuts" user "Board Geometry/Outline")
		(27 "Margin" user)
		(31 "F.CrtYd" user "Package Geometry/Place Bound Top")
		(29 "B.CrtYd" user "Package Geometry/Place Bound Bottom")
		(35 "F.Fab" user "Ref Des/Assembly Top")
		(33 "B.Fab" user "Ref Des/Assembly Bottom")
	)
	(footprint ""
		(layer "F.Cu")
		(at 440.60491 -179.92217)
		(property "Reference" "PL120"
			(at -0.05842 4.39293 0)
			(unlocked yes)
			(layer "F.SilkS")
			(effects
				(font
					(size 0.7874 0.5842)
					(thickness 0.1524)
				)
				(justify left)
			)
		)
		(property "Value" ""
			(at 0 0 0)
			(layer "F.Fab")
			(effects
				(font
					(size 1.27 1.27)
				)
			)
		)
		(duplicate_pad_numbers_are_jumpers no)
		(fp_line
			(start -3.6576 -3.350006)
			(end 3.64998 -3.350006)
			(stroke
				(width 0.1524)
				(type default)
			)
			(layer "F.SilkS")
		)
		(fp_line
			(start -3.64998 -1.8034)
			(end -3.64998 -3.350006)
			(stroke
				(width 0.1524)
				(type default)
			)
			(layer "F.SilkS")
		)
		(fp_line
			(start -3.64998 3.350006)
			(end -3.64998 1.8288)
			(stroke
				(width 0.1524)
				(type default)
			)
			(layer "F.SilkS")
		)
		(fp_line
			(start 3.64998 -3.350006)
			(end 3.64998 -1.8034)
			(stroke
				(width 0.1524)
				(type default)
			)
			(layer "F.SilkS")
		)
		(fp_line
			(start 3.64998 1.8034)
			(end 3.64998 3.350006)
			(stroke
				(width 0.1524)
				(type default)
			)
			(layer "F.SilkS")
		)
		(fp_line
			(start 3.64998 3.350006)
			(end -3.64998 3.350006)
			(stroke
				(width 0.1524)
				(type default)
			)
			(layer "F.SilkS")
		)
		(fp_line
			(start -3.64998 -3.350006)
			(end 3.64998 -3.350006)
			(stroke
				(width 0.1)
				(type default)
			)
			(layer "F.Fab")
		)
		(fp_line
			(start -3.64998 3.350006)
			(end -3.64998 -3.350006)
			(stroke
				(width 0.1)
				(type default)
			)
			(layer "F.Fab")
		)
		(fp_line
			(start 3.64998 -3.350006)
			(end 3.64998 3.350006)
			(stroke
				(width 0.1)
				(type default)
			)
			(layer "F.Fab")
		)
		(fp_line
			(start 3.64998 3.350006)
			(end -3.64998 3.350006)
			(stroke
				(width 0.1)
				(type default)
			)
			(layer "F.Fab")
		)
		(pad "1" smd rect
			(at -2.92481 0)
			(size 2.15392 3.302)
			(layers "F.Cu" "F.Mask" "F.Paste")
			(net "SW_PVNN_MAIN_CPU0_SW")
		)
		(pad "2" smd rect
			(at 2.92481 0)
			(size 2.15392 3.302)
			(layers "F.Cu" "F.Mask" "F.Paste")
			(net "PVNN_MAIN_CPU0")
		)
	)
	(footprint ""
		(layer "F.Cu")
		(at 381.148844 -337.214718 -90)
		(property "Reference" "PC255_P0_5"
			(at 0 0 270)
			(layer "F.SilkS")
			(hide yes)
			(effects
				(font
					(size 1.27 1.27)
				)
			)
		)
		(property "Value" ""
			(at 0 0 270)
			(layer "F.Fab")
			(effects
				(font
					(size 1.27 1.27)
				)
			)
		)
		(duplicate_pad_numbers_are_jumpers no)
		(fp_line
			(start -0.7874 0.4064)
			(end -0.7874 -0.4064)
			(stroke
				(width 0.1524)
				(type default)
			)
			(layer "F.SilkS")
		)
		(fp_line
			(start 0.7874 0.4064)
			(end -0.7874 0.4064)
			(stroke
				(width 0.1524)
				(type default)
			)
			(layer "F.SilkS")
		)
		(fp_line
			(start -0.7874 -0.4064)
			(end 0.7874 -0.4064)
			(stroke
				(width 0.1524)
				(type default)
			)
			(layer "F.SilkS")
		)
		(fp_line
			(start 0.7874 -0.4064)
			(end 0.7874 0.4064)
			(stroke
				(width 0.1524)
				(type default)
			)
			(layer "F.SilkS")
		)
		(fp_line
			(start -0.67945 0.3048)
			(end -0.67945 -0.305054)
			(stroke
				(width 0.1)
				(type default)
			)
			(layer "F.Fab")
		)
		(fp_line
			(start -0.12065 0.3048)
			(end -0.67945 0.3048)
			(stroke
				(width 0.1)
				(type default)
			)
			(layer "F.Fab")
		)
		(fp_line
			(start 0.120396 0.3048)
			(end 0.120396 0.2794)
			(stroke
				(width 0.1)
				(type default)
			)
			(layer "F.Fab")
		)
		(fp_line
			(start 0.67945 0.3048)
			(end 0.120396 0.3048)
			(stroke
				(width 0.1)
				(type default)
			)
			(layer "F.Fab")
		)
		(fp_line
			(start -0.12065 0.2794)
			(end -0.12065 0.3048)
			(stroke
				(width 0.1)
				(type default)
			)
			(layer "F.Fab")
		)
		(fp_line
			(start 0.120396 0.2794)
			(end -0.12065 0.2794)
			(stroke
				(width 0.1)
				(type default)
			)
			(layer "F.Fab")
		)
		(fp_line
			(start -0.12065 -0.2794)
			(end 0.12065 -0.2794)
			(stroke
				(width 0.1)
				(type default)
			)
			(layer "F.Fab")
		)
		(fp_line
			(start 0.12065 -0.2794)
			(end 0.12065 -0.3048)
			(stroke
				(width 0.1)
				(type default)
			)
			(layer "F.Fab")
		)
		(fp_line
			(start 0.12065 -0.3048)
			(end 0.67945 -0.3048)
			(stroke
				(width 0.1)
				(type default)
			)
			(layer "F.Fab")
		)
		(fp_line
			(start 0.67945 -0.3048)
			(end 0.67945 0.3048)
			(stroke
				(width 0.1)
				(type default)
			)
			(layer "F.Fab")
		)
		(fp_line
			(start -0.67945 -0.305054)
			(end -0.12065 -0.305054)
			(stroke
				(width 0.1)
				(type default)
			)
			(layer "F.Fab")
		)
		(fp_line
			(start -0.12065 -0.305054)
			(end -0.12065 -0.2794)
			(stroke
				(width 0.1)
				(type default)
			)
			(layer "F.Fab")
		)
		(pad "1" smd circle
			(at -0.40005 0 270)
			(size 0 0)
			(layers "F.Cu" "F.Mask" "F.Paste")
			(net "SW_P12V_PVCCIN_CPU0_FLT")
		)
		(pad "2" smd circle
			(at 0.40005 0 270)
			(size 0 0)
			(layers "F.Cu" "F.Mask" "F.Paste")
			(net "GND")
		)
	)
	(footprint ""
		(layer "F.Cu")
		(at 189.28588 -133.695948 90)
		(property "Reference" "R1742"
			(at 0 0 90)
			(layer "F.SilkS")
			(hide yes)
			(effects
				(font
					(size 1.27 1.27)
				)
			)
		)
		(property "Value" ""
			(at 0 0 90)
			(layer "F.Fab")
			(effects
				(font
					(size 1.27 1.27)
				)
			)
		)
		(duplicate_pad_numbers_are_jumpers no)
		(fp_line
			(start 0.7874 -0.4064)
			(end 0.7874 0.4064)
			(stroke
				(width 0.1524)
				(type default)
			)
			(layer "F.SilkS")
		)
		(fp_line
			(start -0.7874 -0.4064)
			(end 0.7874 -0.4064)
			(stroke
				(width 0.1524)
				(type default)
			)
			(layer "F.SilkS")
		)
		(fp_line
			(start 0.7874 0.4064)
			(end -0.7874 0.4064)
			(stroke
				(width 0.1524)
				(type default)
			)
			(layer "F.SilkS")
		)
		(fp_line
			(start -0.7874 0.4064)
			(end -0.7874 -0.4064)
			(stroke
				(width 0.1524)
				(type default)
			)
			(layer "F.SilkS")
		)
		(fp_line
			(start -0.12065 -0.305054)
			(end -0.12065 -0.2794)
			(stroke
				(width 0.1)
				(type default)
			)
			(layer "F.Fab")
		)
		(fp_line
			(start -0.67945 -0.305054)
			(end -0.12065 -0.305054)
			(stroke
				(width 0.1)
				(type default)
			)
			(layer "F.Fab")
		)
		(fp_line
			(start 0.67945 -0.3048)
			(end 0.67945 0.3048)
			(stroke
				(width 0.1)
				(type default)
			)
			(layer "F.Fab")
		)
		(fp_line
			(start 0.12065 -0.3048)
			(end 0.67945 -0.3048)
			(stroke
				(width 0.1)
				(type default)
			)
			(layer "F.Fab")
		)
		(fp_line
			(start 0.12065 -0.2794)
			(end 0.12065 -0.3048)
			(stroke
				(width 0.1)
				(type default)
			)
			(layer "F.Fab")
		)
		(fp_line
			(start -0.12065 -0.2794)
			(end 0.12065 -0.2794)
			(stroke
				(width 0.1)
				(type default)
			)
			(layer "F.Fab")
		)
		(fp_line
			(start 0.120396 0.2794)
			(end -0.12065 0.2794)
			(stroke
				(width 0.1)
				(type default)
			)
			(layer "F.Fab")
		)
		(fp_line
			(start -0.12065 0.2794)
			(end -0.12065 0.3048)
			(stroke
				(width 0.1)
				(type default)
			)
			(layer "F.Fab")
		)
		(fp_line
			(start 0.67945 0.3048)
			(end 0.120396 0.3048)
			(stroke
				(width 0.1)
				(type default)
			)
			(layer "F.Fab")
		)
		(fp_line
			(start 0.120396 0.3048)
			(end 0.120396 0.2794)
			(stroke
				(width 0.1)
				(type default)
			)
			(layer "F.Fab")
		)
		(fp_line
			(start -0.12065 0.3048)
			(end -0.67945 0.3048)
			(stroke
				(width 0.1)
				(type default)
			)
			(layer "F.Fab")
		)
		(fp_line
			(start -0.67945 0.3048)
			(end -0.67945 -0.305054)
			(stroke
				(width 0.1)
				(type default)
			)
			(layer "F.Fab")
		)
		(pad "1" smd circle
			(at -0.40005 0 90)
			(size 0 0)
			(layers "F.Cu" "F.Mask" "F.Paste")
			(net "FM_RST_PERST_BIT0")
		)
		(pad "2" smd circle
			(at 0.40005 0 90)
			(size 0 0)
			(layers "F.Cu" "F.Mask" "F.Paste")
			(net "GND")
		)
	)
)
